(kicad_pcb
	(version 20260206)
	(generator "pcbnew")
	(generator_version "10.0")
	(general
		(thickness 1.6)
		(legacy_teardrops no)
	)
	(paper "A4")
	(title_block
		(title "peb — Lightning_PEB_BRD.brd")
		(comment 1 "Lightning (Wiwynn / Facebook NVMe JBOF) / footprints 770-776 of 2563")
	)
	(layers
		(0 "F.Cu" signal "TOP")
		(4 "In1.Cu" signal "L2GND")
		(6 "In2.Cu" signal "L3")
		(8 "In3.Cu" signal "L4VCC")
		(10 "In4.Cu" signal "L5VCC")
		(12 "In5.Cu" signal "L6")
		(14 "In6.Cu" signal "L7GND")
		(2 "B.Cu" signal "BOTTOM")
		(9 "F.Adhes" user "F.Adhesive")
		(11 "B.Adhes" user "B.Adhesive")
		(13 "F.Paste" user "Package Geometry/Pastemask Top")
		(15 "B.Paste" user "Package Geometry/Pastemask Bottom")
		(5 "F.SilkS" user "Ref Des/Silkscreen Top")
		(7 "B.SilkS" user "Ref Des/Silkscreen Bottom")
		(1 "F.Mask" user "Board Geometry/Soldermask Top")
		(3 "B.Mask" user "Board Geometry/Soldermask Bottom")
		(17 "Dwgs.User" user "User.Drawings")
		(19 "Cmts.User" user "User.Comments")
		(21 "Eco1.User" user "User.Eco1")
		(23 "Eco2.User" user "User.Eco2")
		(25 "Edge.Cuts" user "Board Geometry/Outline")
		(27 "Margin" user)
		(31 "F.CrtYd" user "Package Geometry/Place Bound Top")
		(29 "B.CrtYd" user "Package Geometry/Place Bound Bottom")
		(35 "F.Fab" user "Ref Des/Assembly Top")
		(33 "B.Fab" user "Ref Des/Assembly Bottom")
	)
	(footprint ""
		(layer "F.Cu")
		(at 53.303678 -34.1122 90)
		(property "Reference" "Q42"
			(at 0 0 90)
			(layer "F.SilkS")
			(hide yes)
			(effects
				(font
					(size 1.27 1.27)
				)
			)
		)
		(property "Value" "2N7002K-1-GP"
			(at 0.127 -8.9662 90)
			(unlocked yes)
			(layer "F.Fab")
			(hide yes)
			(effects
				(font
					(size 1.016 1.016)
					(thickness 0.1524)
				)
			)
		)
		(property "Device Type" "SOT23DGS2D4H44"
			(at 0.127 -10.4902 90)
			(unlocked yes)
			(layer "F.Fab")
			(hide yes)
			(effects
				(font
					(size 1.016 1.016)
					(thickness 0.1524)
				)
			)
		)
		(duplicate_pad_numbers_are_jumpers no)
		(fp_line
			(start 1.651 -1.778)
			(end -1.651 -1.778)
			(stroke
				(width 0.1524)
				(type default)
			)
			(layer "F.SilkS")
		)
		(fp_line
			(start -1.651 -1.778)
			(end -1.651 1.778)
			(stroke
				(width 0.1524)
				(type default)
			)
			(layer "F.SilkS")
		)
		(fp_line
			(start 1.651 1.778)
			(end 1.651 -1.778)
			(stroke
				(width 0.1524)
				(type default)
			)
			(layer "F.SilkS")
		)
		(fp_line
			(start -1.651 1.778)
			(end 1.651 1.778)
			(stroke
				(width 0.1524)
				(type default)
			)
			(layer "F.SilkS")
		)
		(fp_poly
			(pts
				(xy -1.778 1.941322) (xy -1.778 -1.817878) (xy 1.778 -1.817878) (xy 1.778 1.941322)
			)
			(stroke
				(width 0)
				(type default)
			)
			(fill no)
			(layer "F.CrtYd")
		)
		(fp_poly
			(pts
				(xy -1.778 1.8796) (xy -1.778 -1.8796) (xy 1.778 -1.8796) (xy 1.778 1.8796)
			)
			(stroke
				(width 0)
				(type default)
			)
			(fill no)
			(layer "F.Fab")
		)
		(pad "D" smd custom
			(at 0 -0.9525 90)
			(size 0.1905 0.1905)
			(layers "F.Cu" "F.Mask" "F.Paste")
			(net "Q42_D")
			(options
				(clearance outline)
				(anchor circle)
			)
			(primitives
				(gr_poly
					(pts
						(arc
							(start -0.1778 0.5715)
							(mid -0.321484 0.511984)
							(end -0.381 0.3683)
						)
						(arc
							(start -0.381 -0.3683)
							(mid -0.321484 -0.511984)
							(end -0.1778 -0.5715)
						)
						(arc
							(start 0.1778 -0.5715)
							(mid 0.321484 -0.511984)
							(end 0.381 -0.3683)
						)
						(arc
							(start 0.381 0.3683)
							(mid 0.321484 0.511984)
							(end 0.1778 0.5715)
						)
					)
					(width 0)
					(fill yes)
				)
			)
		)
		(pad "G" smd custom
			(at -0.98425 0.9525 90)
			(size 0.1905 0.1905)
			(layers "F.Cu" "F.Mask" "F.Paste")
			(net "P3V3_STBY_PG")
			(options
				(clearance outline)
				(anchor circle)
			)
			(primitives
				(gr_poly
					(pts
						(arc
							(start -0.1778 0.5715)
							(mid -0.321484 0.511984)
							(end -0.381 0.3683)
						)
						(arc
							(start -0.381 -0.3683)
							(mid -0.321484 -0.511984)
							(end -0.1778 -0.5715)
						)
						(arc
							(start 0.1778 -0.5715)
							(mid 0.321484 -0.511984)
							(end 0.381 -0.3683)
						)
						(arc
							(start 0.381 0.3683)
							(mid 0.321484 0.511984)
							(end 0.1778 0.5715)
						)
					)
					(width 0)
					(fill yes)
				)
			)
		)
		(pad "S" smd custom
			(at 0.98425 0.9525 90)
			(size 0.1905 0.1905)
			(layers "F.Cu" "F.Mask" "F.Paste")
			(net "GND")
			(options
				(clearance outline)
				(anchor circle)
			)
			(primitives
				(gr_poly
					(pts
						(arc
							(start -0.1778 0.5715)
							(mid -0.321484 0.511984)
							(end -0.381 0.3683)
						)
						(arc
							(start -0.381 -0.3683)
							(mid -0.321484 -0.511984)
							(end -0.1778 -0.5715)
						)
						(arc
							(start 0.1778 -0.5715)
							(mid 0.321484 -0.511984)
							(end 0.381 -0.3683)
						)
						(arc
							(start 0.381 0.3683)
							(mid 0.321484 0.511984)
							(end 0.1778 0.5715)
						)
					)
					(width 0)
					(fill yes)
				)
			)
		)
	)
	(footprint ""
		(layer "F.Cu")
		(at 187.21832 -27.79014 90)
		(property "Reference" "R632"
			(at 0 0 90)
			(layer "F.SilkS")
			(hide yes)
			(effects
				(font
					(size 1.27 1.27)
				)
			)
		)
		(property "Value" "0R2J-2-GP"
			(at 0.064008 -3.993896 90)
			(unlocked yes)
			(layer "F.Fab")
			(hide yes)
			(effects
				(font
					(size 1.016 1.016)
					(thickness 0.1524)
				)
			)
		)
		(property "Device Type" "R402H16"
			(at 0.064008 -5.517896 90)
			(unlocked yes)
			(layer "F.Fab")
			(hide yes)
			(effects
				(font
					(size 1.016 1.016)
					(thickness 0.1524)
				)
			)
		)
		(duplicate_pad_numbers_are_jumpers no)
		(fp_line
			(start 0.508 -0.9398)
			(end -0.508 -0.9398)
			(stroke
				(width 0.1524)
				(type default)
			)
			(layer "F.SilkS")
		)
		(fp_line
			(start -0.508 -0.9398)
			(end -0.508 0.9398)
			(stroke
				(width 0.1524)
				(type default)
			)
			(layer "F.SilkS")
		)
		(fp_rect
			(start -0.508 0.9398)
			(end 0.508 -0.9398)
			(stroke
				(width 0)
				(type default)
			)
			(fill no)
			(layer "F.CrtYd")
		)
		(fp_rect
			(start -0.508 0.9398)
			(end 0.508 -0.9398)
			(stroke
				(width 0)
				(type default)
			)
			(fill no)
			(layer "F.Fab")
		)
		(pad "1" smd custom
			(at 0 -0.4445 90)
			(size 0.1397 0.1397)
			(layers "F.Cu" "F.Mask" "F.Paste")
			(net "8644_USB_DP4")
			(options
				(clearance outline)
				(anchor circle)
			)
			(primitives
				(gr_poly
					(pts
						(arc
							(start -0.1778 -0.2794)
							(mid -0.249642 -0.249642)
							(end -0.2794 -0.1778)
						)
						(arc
							(start -0.2794 0.1778)
							(mid -0.249642 0.249642)
							(end -0.1778 0.2794)
						)
						(arc
							(start 0.1778 0.2794)
							(mid 0.249642 0.249642)
							(end 0.2794 0.1778)
						)
						(arc
							(start 0.2794 -0.1778)
							(mid 0.249642 -0.249642)
							(end 0.1778 -0.2794)
						)
					)
					(width 0)
					(fill yes)
				)
			)
		)
		(pad "2" smd custom
			(at 0 0.4445 90)
			(size 0.1397 0.1397)
			(layers "F.Cu" "F.Mask" "F.Paste")
			(net "P3V3_STBY")
			(options
				(clearance outline)
				(anchor circle)
			)
			(primitives
				(gr_poly
					(pts
						(arc
							(start -0.1778 -0.2794)
							(mid -0.249642 -0.249642)
							(end -0.2794 -0.1778)
						)
						(arc
							(start -0.2794 0.1778)
							(mid -0.249642 0.249642)
							(end -0.1778 0.2794)
						)
						(arc
							(start 0.1778 0.2794)
							(mid 0.249642 0.249642)
							(end 0.2794 0.1778)
						)
						(arc
							(start 0.2794 -0.1778)
							(mid 0.249642 -0.249642)
							(end 0.1778 -0.2794)
						)
					)
					(width 0)
					(fill yes)
				)
			)
		)
	)
	(footprint ""
		(layer "F.Cu")
		(at 162.052 -33.528)
		(property "Reference" "C401"
			(at 0 0 0)
			(layer "F.SilkS")
			(hide yes)
			(effects
				(font
					(size 1.27 1.27)
				)
			)
		)
		(property "Value" "SCD22U10V2KX-1GP"
			(at 1.1811 -2.7051 0)
			(unlocked yes)
			(layer "F.Fab")
			(hide yes)
			(effects
				(font
					(size 1.016 1.016)
					(thickness 0.1524)
				)
			)
		)
		(property "Device Type" "C402H22"
			(at 1.1811 -4.2291 0)
			(unlocked yes)
			(layer "F.Fab")
			(hide yes)
			(effects
				(font
					(size 1.016 1.016)
					(thickness 0.1524)
				)
			)
		)
		(duplicate_pad_numbers_are_jumpers no)
		(fp_rect
			(start -0.4318 0.9525)
			(end 0.4318 -0.9525)
			(stroke
				(width 0)
				(type default)
			)
			(fill no)
			(layer "F.CrtYd")
		)
		(fp_rect
			(start -0.4318 0.9525)
			(end 0.4318 -0.9525)
			(stroke
				(width 0)
				(type default)
			)
			(fill no)
			(layer "F.Fab")
		)
		(pad "1" smd custom
			(at 0 -0.4445)
			(size 0.1524 0.1524)
			(layers "F.Cu" "F.Mask" "F.Paste")
			(net "PCIE_TX_CAP_N90")
			(options
				(clearance outline)
				(anchor circle)
			)
			(primitives
				(gr_poly
					(pts
						(arc
							(start 0.3048 -0.2032)
							(mid 0.275042 -0.275042)
							(end 0.2032 -0.3048)
						)
						(arc
							(start -0.2032 -0.3048)
							(mid -0.275042 -0.275042)
							(end -0.3048 -0.2032)
						)
						(arc
							(start -0.3048 0.2032)
							(mid -0.275042 0.275042)
							(end -0.2032 0.3048)
						)
						(arc
							(start 0.2032 0.3048)
							(mid 0.275042 0.275042)
							(end 0.3048 0.2032)
						)
					)
					(width 0)
					(fill yes)
				)
			)
		)
		(pad "2" smd custom
			(at 0 0.4445)
			(size 0.1524 0.1524)
			(layers "F.Cu" "F.Mask" "F.Paste")
			(net "PCIE_TX_N90")
			(options
				(clearance outline)
				(anchor circle)
			)
			(primitives
				(gr_poly
					(pts
						(arc
							(start 0.3048 -0.2032)
							(mid 0.275042 -0.275042)
							(end 0.2032 -0.3048)
						)
						(arc
							(start -0.2032 -0.3048)
							(mid -0.275042 -0.275042)
							(end -0.3048 -0.2032)
						)
						(arc
							(start -0.3048 0.2032)
							(mid -0.275042 0.275042)
							(end -0.2032 0.3048)
						)
						(arc
							(start 0.2032 0.3048)
							(mid 0.275042 0.275042)
							(end 0.3048 0.2032)
						)
					)
					(width 0)
					(fill yes)
				)
			)
		)
	)
	(footprint ""
		(layer "F.Cu")
		(at 22.479 -164.084 -90)
		(property "Reference" "R510"
			(at 0 0 270)
			(layer "F.SilkS")
			(hide yes)
			(effects
				(font
					(size 1.27 1.27)
				)
			)
		)
		(property "Value" "0R2J-2-GP"
			(at 0.064008 -3.993896 270)
			(unlocked yes)
			(layer "F.Fab")
			(hide yes)
			(effects
				(font
					(size 1.016 1.016)
					(thickness 0.1524)
				)
			)
		)
		(property "Device Type" "R402H16"
			(at 0.064008 -5.517896 270)
			(unlocked yes)
			(layer "F.Fab")
			(hide yes)
			(effects
				(font
					(size 1.016 1.016)
					(thickness 0.1524)
				)
			)
		)
		(duplicate_pad_numbers_are_jumpers no)
		(fp_line
			(start -0.508 -0.9398)
			(end -0.508 0.9398)
			(stroke
				(width 0.1524)
				(type default)
			)
			(layer "F.SilkS")
		)
		(fp_line
			(start 0.508 -0.9398)
			(end -0.508 -0.9398)
			(stroke
				(width 0.1524)
				(type default)
			)
			(layer "F.SilkS")
		)
		(fp_rect
			(start -0.508 0.9398)
			(end 0.508 -0.9398)
			(stroke
				(width 0)
				(type default)
			)
			(fill no)
			(layer "F.CrtYd")
		)
		(fp_rect
			(start -0.508 0.9398)
			(end 0.508 -0.9398)
			(stroke
				(width 0)
				(type default)
			)
			(fill no)
			(layer "F.Fab")
		)
		(pad "1" smd custom
			(at 0 -0.4445 270)
			(size 0.1397 0.1397)
			(layers "F.Cu" "F.Mask" "F.Paste")
			(net "BMC_RESET#_DDR3")
			(options
				(clearance outline)
				(anchor circle)
			)
			(primitives
				(gr_poly
					(pts
						(arc
							(start -0.1778 -0.2794)
							(mid -0.249642 -0.249642)
							(end -0.2794 -0.1778)
						)
						(arc
							(start -0.2794 0.1778)
							(mid -0.249642 0.249642)
							(end -0.1778 0.2794)
						)
						(arc
							(start 0.1778 0.2794)
							(mid 0.249642 0.249642)
							(end 0.2794 0.1778)
						)
						(arc
							(start 0.2794 -0.1778)
							(mid 0.249642 -0.249642)
							(end 0.1778 -0.2794)
						)
					)
					(width 0)
					(fill yes)
				)
			)
		)
		(pad "2" smd custom
			(at 0 0.4445 270)
			(size 0.1397 0.1397)
			(layers "F.Cu" "F.Mask" "F.Paste")
			(net "GPIOB1")
			(options
				(clearance outline)
				(anchor circle)
			)
			(primitives
				(gr_poly
					(pts
						(arc
							(start -0.1778 -0.2794)
							(mid -0.249642 -0.249642)
							(end -0.2794 -0.1778)
						)
						(arc
							(start -0.2794 0.1778)
							(mid -0.249642 0.249642)
							(end -0.1778 0.2794)
						)
						(arc
							(start 0.1778 0.2794)
							(mid 0.249642 0.249642)
							(end 0.2794 0.1778)
						)
						(arc
							(start 0.2794 -0.1778)
							(mid 0.249642 -0.249642)
							(end 0.1778 -0.2794)
						)
					)
					(width 0)
					(fill yes)
				)
			)
		)
	)
	(footprint ""
		(layer "F.Cu")
		(at 72.747124 -183.235092)
		(property "Reference" "R7937"
			(at 0 0 0)
			(layer "F.SilkS")
			(hide yes)
			(effects
				(font
					(size 1.27 1.27)
				)
			)
		)
		(property "Value" "0R2J-2-GP"
			(at 0.064008 -3.993896 0)
			(unlocked yes)
			(layer "F.Fab")
			(hide yes)
			(effects
				(font
					(size 1.016 1.016)
					(thickness 0.1524)
				)
			)
		)
		(property "Device Type" "R402H16"
			(at 0.064008 -5.517896 0)
			(unlocked yes)
			(layer "F.Fab")
			(hide yes)
			(effects
				(font
					(size 1.016 1.016)
					(thickness 0.1524)
				)
			)
		)
		(duplicate_pad_numbers_are_jumpers no)
		(fp_line
			(start -0.508 -0.9398)
			(end -0.508 0.9398)
			(stroke
				(width 0.1524)
				(type default)
			)
			(layer "F.SilkS")
		)
		(fp_line
			(start 0.508 -0.9398)
			(end -0.508 -0.9398)
			(stroke
				(width 0.1524)
				(type default)
			)
			(layer "F.SilkS")
		)
		(fp_rect
			(start -0.508 0.9398)
			(end 0.508 -0.9398)
			(stroke
				(width 0)
				(type default)
			)
			(fill no)
			(layer "F.CrtYd")
		)
		(fp_rect
			(start -0.508 0.9398)
			(end 0.508 -0.9398)
			(stroke
				(width 0)
				(type default)
			)
			(fill no)
			(layer "F.Fab")
		)
		(pad "1" smd custom
			(at 0 -0.4445)
			(size 0.1397 0.1397)
			(layers "F.Cu" "F.Mask" "F.Paste")
			(net "SSD_ATNLED#0")
			(options
				(clearance outline)
				(anchor circle)
			)
			(primitives
				(gr_poly
					(pts
						(arc
							(start -0.1778 -0.2794)
							(mid -0.249642 -0.249642)
							(end -0.2794 -0.1778)
						)
						(arc
							(start -0.2794 0.1778)
							(mid -0.249642 0.249642)
							(end -0.1778 0.2794)
						)
						(arc
							(start 0.1778 0.2794)
							(mid 0.249642 0.249642)
							(end 0.2794 0.1778)
						)
						(arc
							(start 0.2794 -0.1778)
							(mid 0.249642 -0.249642)
							(end 0.1778 -0.2794)
						)
					)
					(width 0)
					(fill yes)
				)
			)
		)
		(pad "2" smd custom
			(at 0 0.4445)
			(size 0.1397 0.1397)
			(layers "F.Cu" "F.Mask" "F.Paste")
			(net "SSD_ATNLED#0_R")
			(options
				(clearance outline)
				(anchor circle)
			)
			(primitives
				(gr_poly
					(pts
						(arc
							(start -0.1778 -0.2794)
							(mid -0.249642 -0.249642)
							(end -0.2794 -0.1778)
						)
						(arc
							(start -0.2794 0.1778)
							(mid -0.249642 0.249642)
							(end -0.1778 0.2794)
						)
						(arc
							(start 0.1778 0.2794)
							(mid 0.249642 0.249642)
							(end 0.2794 0.1778)
						)
						(arc
							(start 0.2794 -0.1778)
							(mid 0.249642 -0.249642)
							(end 0.1778 -0.2794)
						)
					)
					(width 0)
					(fill yes)
				)
			)
		)
	)
	(footprint ""
		(layer "F.Cu")
		(at 42.164 -205.359 -90)
		(property "Reference" "R878"
			(at 0 0 270)
			(layer "F.SilkS")
			(hide yes)
			(effects
				(font
					(size 1.27 1.27)
				)
			)
		)
		(property "Value" "4K7R2J-2-GP"
			(at 0.064008 -3.993896 270)
			(unlocked yes)
			(layer "F.Fab")
			(hide yes)
			(effects
				(font
					(size 1.016 1.016)
					(thickness 0.1524)
				)
			)
		)
		(property "Device Type" "R402H16"
			(at 0.064008 -5.517896 270)
			(unlocked yes)
			(layer "F.Fab")
			(hide yes)
			(effects
				(font
					(size 1.016 1.016)
					(thickness 0.1524)
				)
			)
		)
		(duplicate_pad_numbers_are_jumpers no)
		(fp_line
			(start -0.508 -0.9398)
			(end -0.508 0.9398)
			(stroke
				(width 0.1524)
				(type default)
			)
			(layer "F.SilkS")
		)
		(fp_line
			(start 0.508 -0.9398)
			(end -0.508 -0.9398)
			(stroke
				(width 0.1524)
				(type default)
			)
			(layer "F.SilkS")
		)
		(fp_rect
			(start -0.508 0.9398)
			(end 0.508 -0.9398)
			(stroke
				(width 0)
				(type default)
			)
			(fill no)
			(layer "F.CrtYd")
		)
		(fp_rect
			(start -0.508 0.9398)
			(end 0.508 -0.9398)
			(stroke
				(width 0)
				(type default)
			)
			(fill no)
			(layer "F.Fab")
		)
		(pad "1" smd custom
			(at 0 -0.4445 270)
			(size 0.1397 0.1397)
			(layers "F.Cu" "F.Mask" "F.Paste")
			(net "P3V3_STBY")
			(options
				(clearance outline)
				(anchor circle)
			)
			(primitives
				(gr_poly
					(pts
						(arc
							(start -0.1778 -0.2794)
							(mid -0.249642 -0.249642)
							(end -0.2794 -0.1778)
						)
						(arc
							(start -0.2794 0.1778)
							(mid -0.249642 0.249642)
							(end -0.1778 0.2794)
						)
						(arc
							(start 0.1778 0.2794)
							(mid 0.249642 0.249642)
							(end 0.2794 0.1778)
						)
						(arc
							(start 0.2794 -0.1778)
							(mid 0.249642 -0.249642)
							(end 0.1778 -0.2794)
						)
					)
					(width 0)
					(fill yes)
				)
			)
		)
		(pad "2" smd custom
			(at 0 0.4445 270)
			(size 0.1397 0.1397)
			(layers "F.Cu" "F.Mask" "F.Paste")
			(net "BUF_I2C6_C_FCB_SCL_R")
			(options
				(clearance outline)
				(anchor circle)
			)
			(primitives
				(gr_poly
					(pts
						(arc
							(start -0.1778 -0.2794)
							(mid -0.249642 -0.249642)
							(end -0.2794 -0.1778)
						)
						(arc
							(start -0.2794 0.1778)
							(mid -0.249642 0.249642)
							(end -0.1778 0.2794)
						)
						(arc
							(start 0.1778 0.2794)
							(mid 0.249642 0.249642)
							(end 0.2794 0.1778)
						)
						(arc
							(start 0.2794 -0.1778)
							(mid 0.249642 -0.249642)
							(end 0.1778 -0.2794)
						)
					)
					(width 0)
					(fill yes)
				)
			)
		)
	)
	(footprint ""
		(layer "F.Cu")
		(at 19.76247 -91.624658 90)
		(property "Reference" "R2941"
			(at 0 0 90)
			(layer "F.SilkS")
			(hide yes)
			(effects
				(font
					(size 1.27 1.27)
				)
			)
		)
		(property "Value" "10KR2F-2-GP"
			(at 0.064008 -3.993896 90)
			(unlocked yes)
			(layer "F.Fab")
			(hide yes)
			(effects
				(font
					(size 1.016 1.016)
					(thickness 0.1524)
				)
			)
		)
		(property "Device Type" "R402H16"
			(at 0.064008 -5.517896 90)
			(unlocked yes)
			(layer "F.Fab")
			(hide yes)
			(effects
				(font
					(size 1.016 1.016)
					(thickness 0.1524)
				)
			)
		)
		(duplicate_pad_numbers_are_jumpers no)
		(fp_line
			(start 0.508 -0.9398)
			(end -0.508 -0.9398)
			(stroke
				(width 0.1524)
				(type default)
			)
			(layer "F.SilkS")
		)
		(fp_line
			(start -0.508 -0.9398)
			(end -0.508 0.9398)
			(stroke
				(width 0.1524)
				(type default)
			)
			(layer "F.SilkS")
		)
		(fp_rect
			(start -0.508 0.9398)
			(end 0.508 -0.9398)
			(stroke
				(width 0)
				(type default)
			)
			(fill no)
			(layer "F.CrtYd")
		)
		(fp_rect
			(start -0.508 0.9398)
			(end 0.508 -0.9398)
			(stroke
				(width 0)
				(type default)
			)
			(fill no)
			(layer "F.Fab")
		)
		(pad "1" smd custom
			(at 0 -0.4445 90)
			(size 0.1397 0.1397)
			(layers "F.Cu" "F.Mask" "F.Paste")
			(net "P3V3_STBY")
			(options
				(clearance outline)
				(anchor circle)
			)
			(primitives
				(gr_poly
					(pts
						(arc
							(start -0.1778 -0.2794)
							(mid -0.249642 -0.249642)
							(end -0.2794 -0.1778)
						)
						(arc
							(start -0.2794 0.1778)
							(mid -0.249642 0.249642)
							(end -0.1778 0.2794)
						)
						(arc
							(start 0.1778 0.2794)
							(mid 0.249642 0.249642)
							(end 0.2794 0.1778)
						)
						(arc
							(start 0.2794 -0.1778)
							(mid 0.249642 -0.249642)
							(end 0.1778 -0.2794)
						)
					)
					(width 0)
					(fill yes)
				)
			)
		)
		(pad "2" smd custom
			(at 0 0.4445 90)
			(size 0.1397 0.1397)
			(layers "F.Cu" "F.Mask" "F.Paste")
			(net "FM_TPM_PRES_RST_N")
			(options
				(clearance outline)
				(anchor circle)
			)
			(primitives
				(gr_poly
					(pts
						(arc
							(start -0.1778 -0.2794)
							(mid -0.249642 -0.249642)
							(end -0.2794 -0.1778)
						)
						(arc
							(start -0.2794 0.1778)
							(mid -0.249642 0.249642)
							(end -0.1778 0.2794)
						)
						(arc
							(start 0.1778 0.2794)
							(mid 0.249642 0.249642)
							(end 0.2794 0.1778)
						)
						(arc
							(start 0.2794 -0.1778)
							(mid 0.249642 -0.249642)
							(end 0.1778 -0.2794)
						)
					)
					(width 0)
					(fill yes)
				)
			)
		)
	)
)
